# S9S_MB_2U (Grand Teton) — schematic netlist excerpt (pin names and nets, part order shuffled) for the footprints in the layout excerpt that follows; sources: Cadence DE-HDL packaged netlist, KiCad conversion of 03242023_DA0F0TMBIJ0_F0T_Motherboard_J_brd_V01_OCP.brd

R4489  Q_RES  4.75K 1% CHIP  pkg 0402LF  page 211 : A = P3V3 ; B = CLK_9ZXL045_SADR0
R330  Q_RES  0 CHIP  pkg 1206LF  page 80 : A = PVNN_MAIN_CPU1 ; B = PVNN_TERM_CPU1
R331  Q_RES  1K 1% EMPTY  pkg 0402LF  page 127 : A = P3V3_AUX ; B = PD_PIROM_CPU0_ADDR2

(kicad_pcb
	(version 20260206)
	(generator "pcbnew")
	(generator_version "10.0")
	(general
		(thickness 1.6)
		(legacy_teardrops no)
	)
	(paper "A4")
	(title_block
		(title "03242023_DA0F0TMBIJ0_F0T_Motherboard_J_brd_V01_OCP.brd")
		(comment 1 "Grand Teton / footprints 3773-3775 of 6105")
	)
	(layers
		(0 "F.Cu" signal "TOP")
		(4 "In1.Cu" signal "GND")
		(6 "In2.Cu" signal "IN1")
		(8 "In3.Cu" signal "GND1")
		(10 "In4.Cu" signal "IN2")
		(12 "In5.Cu" signal "GND2")
		(14 "In6.Cu" signal "IN3")
		(16 "In7.Cu" signal "GND3")
		(18 "In8.Cu" signal "VCC")
		(20 "In9.Cu" signal "VCC1")
		(22 "In10.Cu" signal "GND4")
		(24 "In11.Cu" signal "IN4")
		(26 "In12.Cu" signal "GND5")
		(28 "In13.Cu" signal "IN5")
		(30 "In14.Cu" signal "GND6")
		(32 "In15.Cu" signal "IN6")
		(34 "In16.Cu" signal "GND7")
		(2 "B.Cu" signal "BOTTOM")
		(9 "F.Adhes" user "F.Adhesive")
		(11 "B.Adhes" user "B.Adhesive")
		(13 "F.Paste" user "Package Geometry/Pastemask Top")
		(15 "B.Paste" user "Package Geometry/Pastemask Bottom")
		(5 "F.SilkS" user "Ref Des/Silkscreen Top")
		(7 "B.SilkS" user "Ref Des/Silkscreen Bottom")
		(1 "F.Mask" user "Board Geometry/Soldermask Top")
		(3 "B.Mask" user "Board Geometry/Soldermask Bottom")
		(17 "Dwgs.User" user "User.Drawings")
		(19 "Cmts.User" user "User.Comments")
		(21 "Eco1.User" user "User.Eco1")
		(23 "Eco2.User" user "User.Eco2")
		(25 "Edge.Cuts" user "Board Geometry/Outline")
		(27 "Margin" user)
		(31 "F.CrtYd" user "Package Geometry/Place Bound Top")
		(29 "B.CrtYd" user "Package Geometry/Place Bound Bottom")
		(35 "F.Fab" user "Ref Des/Assembly Top")
		(33 "B.Fab" user "Ref Des/Assembly Bottom")
	)
	(footprint ""
		(layer "F.Cu")
		(at 120.10644 -414.274762 180)
		(property "Reference" "R4489"
			(at 0 0 180)
			(layer "F.SilkS")
			(hide yes)
			(effects
				(font
					(size 1.27 1.27)
				)
			)
		)
		(property "Value" ""
			(at 0 0 180)
			(layer "F.Fab")
			(effects
				(font
					(size 1.27 1.27)
				)
			)
		)
		(duplicate_pad_numbers_are_jumpers no)
		(fp_line
			(start 0.7874 0.4064)
			(end -0.7874 0.4064)
			(stroke
				(width 0.1524)
				(type default)
			)
			(layer "F.SilkS")
		)
		(fp_line
			(start 0.7874 -0.4064)
			(end 0.7874 0.4064)
			(stroke
				(width 0.1524)
				(type default)
			)
			(layer "F.SilkS")
		)
		(fp_line
			(start -0.7874 0.4064)
			(end -0.7874 -0.4064)
			(stroke
				(width 0.1524)
				(type default)
			)
			(layer "F.SilkS")
		)
		(fp_line
			(start -0.7874 -0.4064)
			(end 0.7874 -0.4064)
			(stroke
				(width 0.1524)
				(type default)
			)
			(layer "F.SilkS")
		)
		(fp_line
			(start 0.67945 0.3048)
			(end 0.120396 0.3048)
			(stroke
				(width 0.1)
				(type default)
			)
			(layer "F.Fab")
		)
		(fp_line
			(start 0.67945 -0.3048)
			(end 0.67945 0.3048)
			(stroke
				(width 0.1)
				(type default)
			)
			(layer "F.Fab")
		)
		(fp_line
			(start 0.12065 -0.2794)
			(end 0.12065 -0.3048)
			(stroke
				(width 0.1)
				(type default)
			)
			(layer "F.Fab")
		)
		(fp_line
			(start 0.12065 -0.3048)
			(end 0.67945 -0.3048)
			(stroke
				(width 0.1)
				(type default)
			)
			(layer "F.Fab")
		)
		(fp_line
			(start 0.120396 0.3048)
			(end 0.120396 0.2794)
			(stroke
				(width 0.1)
				(type default)
			)
			(layer "F.Fab")
		)
		(fp_line
			(start 0.120396 0.2794)
			(end -0.12065 0.2794)
			(stroke
				(width 0.1)
				(type default)
			)
			(layer "F.Fab")
		)
		(fp_line
			(start -0.12065 0.3048)
			(end -0.67945 0.3048)
			(stroke
				(width 0.1)
				(type default)
			)
			(layer "F.Fab")
		)
		(fp_line
			(start -0.12065 0.2794)
			(end -0.12065 0.3048)
			(stroke
				(width 0.1)
				(type default)
			)
			(layer "F.Fab")
		)
		(fp_line
			(start -0.12065 -0.2794)
			(end 0.12065 -0.2794)
			(stroke
				(width 0.1)
				(type default)
			)
			(layer "F.Fab")
		)
		(fp_line
			(start -0.12065 -0.305054)
			(end -0.12065 -0.2794)
			(stroke
				(width 0.1)
				(type default)
			)
			(layer "F.Fab")
		)
		(fp_line
			(start -0.67945 0.3048)
			(end -0.67945 -0.305054)
			(stroke
				(width 0.1)
				(type default)
			)
			(layer "F.Fab")
		)
		(fp_line
			(start -0.67945 -0.305054)
			(end -0.12065 -0.305054)
			(stroke
				(width 0.1)
				(type default)
			)
			(layer "F.Fab")
		)
		(pad "1" smd circle
			(at -0.40005 0 180)
			(size 0 0)
			(layers "F.Cu" "F.Mask" "F.Paste")
			(net "P3V3")
		)
		(pad "2" smd circle
			(at 0.40005 0 180)
			(size 0 0)
			(layers "F.Cu" "F.Mask" "F.Paste")
			(net "CLK_9ZXL045_SADR0")
		)
	)
	(footprint ""
		(layer "F.Cu")
		(at 44.29125 -181.983634)
		(property "Reference" "R330"
			(at 0 0 0)
			(layer "F.SilkS")
			(hide yes)
			(effects
				(font
					(size 1.27 1.27)
				)
			)
		)
		(property "Value" ""
			(at 0 0 0)
			(layer "F.Fab")
			(effects
				(font
					(size 1.27 1.27)
				)
			)
		)
		(duplicate_pad_numbers_are_jumpers no)
		(fp_line
			(start -2.044192 -0.94361)
			(end -2.044192 0.898398)
			(stroke
				(width 0.1524)
				(type default)
			)
			(layer "F.SilkS")
		)
		(fp_line
			(start -2.044192 0.94361)
			(end 2.044192 0.94361)
			(stroke
				(width 0.1524)
				(type default)
			)
			(layer "F.SilkS")
		)
		(fp_line
			(start 2.044192 -0.94361)
			(end -2.044192 -0.94361)
			(stroke
				(width 0.1524)
				(type default)
			)
			(layer "F.SilkS")
		)
		(fp_line
			(start 2.044192 0.94361)
			(end 2.044192 -0.94361)
			(stroke
				(width 0.1524)
				(type default)
			)
			(layer "F.SilkS")
		)
		(fp_line
			(start -1.625092 -0.87503)
			(end -1.625092 0.87503)
			(stroke
				(width 0.1)
				(type default)
			)
			(layer "F.Fab")
		)
		(fp_line
			(start -1.625092 0.87503)
			(end 1.625092 0.87503)
			(stroke
				(width 0.1)
				(type default)
			)
			(layer "F.Fab")
		)
		(fp_line
			(start 1.625092 -0.87503)
			(end -1.625092 -0.87503)
			(stroke
				(width 0.1)
				(type default)
			)
			(layer "F.Fab")
		)
		(fp_line
			(start 1.625092 0.87503)
			(end 1.625092 -0.87503)
			(stroke
				(width 0.1)
				(type default)
			)
			(layer "F.Fab")
		)
		(pad "1" smd rect
			(at -1.450086 0)
			(size 0.9144 1.6002)
			(layers "F.Cu" "F.Mask" "F.Paste")
			(net "PVNN_MAIN_CPU1")
		)
		(pad "2" smd rect
			(at 1.450086 0)
			(size 0.9144 1.6002)
			(layers "F.Cu" "F.Mask" "F.Paste")
			(net "PVNN_TERM_CPU1")
		)
	)
	(footprint ""
		(layer "F.Cu")
		(at 406.124664 -361.865926 180)
		(property "Reference" "R331"
			(at 0 0 180)
			(layer "F.SilkS")
			(hide yes)
			(effects
				(font
					(size 1.27 1.27)
				)
			)
		)
		(property "Value" ""
			(at 0 0 180)
			(layer "F.Fab")
			(effects
				(font
					(size 1.27 1.27)
				)
			)
		)
		(duplicate_pad_numbers_are_jumpers no)
		(fp_line
			(start 0.7874 0.4064)
			(end -0.7874 0.4064)
			(stroke
				(width 0.1524)
				(type default)
			)
			(layer "F.SilkS")
		)
		(fp_line
			(start 0.7874 -0.4064)
			(end 0.7874 0.4064)
			(stroke
				(width 0.1524)
				(type default)
			)
			(layer "F.SilkS")
		)
		(fp_line
			(start -0.7874 0.4064)
			(end -0.7874 -0.4064)
			(stroke
				(width 0.1524)
				(type default)
			)
			(layer "F.SilkS")
		)
		(fp_line
			(start -0.7874 -0.4064)
			(end 0.7874 -0.4064)
			(stroke
				(width 0.1524)
				(type default)
			)
			(layer "F.SilkS")
		)
		(fp_line
			(start 0.67945 0.3048)
			(end 0.120396 0.3048)
			(stroke
				(width 0.1)
				(type default)
			)
			(layer "F.Fab")
		)
		(fp_line
			(start 0.67945 -0.3048)
			(end 0.67945 0.3048)
			(stroke
				(width 0.1)
				(type default)
			)
			(layer "F.Fab")
		)
		(fp_line
			(start 0.12065 -0.2794)
			(end 0.12065 -0.3048)
			(stroke
				(width 0.1)
				(type default)
			)
			(layer "F.Fab")
		)
		(fp_line
			(start 0.12065 -0.3048)
			(end 0.67945 -0.3048)
			(stroke
				(width 0.1)
				(type default)
			)
			(layer "F.Fab")
		)
		(fp_line
			(start 0.120396 0.3048)
			(end 0.120396 0.2794)
			(stroke
				(width 0.1)
				(type default)
			)
			(layer "F.Fab")
		)
		(fp_line
			(start 0.120396 0.2794)
			(end -0.12065 0.2794)
			(stroke
				(width 0.1)
				(type default)
			)
			(layer "F.Fab")
		)
		(fp_line
			(start -0.12065 0.3048)
			(end -0.67945 0.3048)
			(stroke
				(width 0.1)
				(type default)
			)
			(layer "F.Fab")
		)
		(fp_line
			(start -0.12065 0.2794)
			(end -0.12065 0.3048)
			(stroke
				(width 0.1)
				(type default)
			)
			(layer "F.Fab")
		)
		(fp_line
			(start -0.12065 -0.2794)
			(end 0.12065 -0.2794)
			(stroke
				(width 0.1)
				(type default)
			)
			(layer "F.Fab")
		)
		(fp_line
			(start -0.12065 -0.305054)
			(end -0.12065 -0.2794)
			(stroke
				(width 0.1)
				(type default)
			)
			(layer "F.Fab")
		)
		(fp_line
			(start -0.67945 0.3048)
			(end -0.67945 -0.305054)
			(stroke
				(width 0.1)
				(type default)
			)
			(layer "F.Fab")
		)
		(fp_line
			(start -0.67945 -0.305054)
			(end -0.12065 -0.305054)
			(stroke
				(width 0.1)
				(type default)
			)
			(layer "F.Fab")
		)
		(pad "1" smd circle
			(at -0.40005 0 180)
			(size 0 0)
			(layers "F.Cu" "F.Mask" "F.Paste")
			(net "P3V3_AUX")
		)
		(pad "2" smd circle
			(at 0.40005 0 180)
			(size 0 0)
			(layers "F.Cu" "F.Mask" "F.Paste")
			(net "PD_PIROM_CPU0_ADDR2")
		)
	)
)
